(kicad_pcb
	(version 20260206)
	(generator "pcbnew")
	(generator_version "10.0")
	(general
		(thickness 1.6)
		(legacy_teardrops no)
	)
	(paper "A4")
	(title_block
		(title "01162023_DA0F0TEBIF0_F0T_Expander_BD_F_brd_V02_OCP.brd")
		(comment 1 "Grand Teton / footprints 9190-9199 of 9728")
	)
	(layers
		(0 "F.Cu" signal "TOP")
		(4 "In1.Cu" signal "GND")
		(6 "In2.Cu" signal "VCC")
		(8 "In3.Cu" signal "VCC1")
		(10 "In4.Cu" signal "GND1")
		(12 "In5.Cu" signal "IN1")
		(14 "In6.Cu" signal "GND2")
		(16 "In7.Cu" signal "IN2")
		(18 "In8.Cu" signal "GND3")
		(20 "In9.Cu" signal "IN3")
		(22 "In10.Cu" signal "GND4")
		(24 "In11.Cu" signal "IN4")
		(26 "In12.Cu" signal "GND5")
		(28 "In13.Cu" signal "IN5")
		(30 "In14.Cu" signal "GND6")
		(32 "In15.Cu" signal "IN6")
		(34 "In16.Cu" signal "GND7")
		(2 "B.Cu" signal "BOTTOM")
		(9 "F.Adhes" user "F.Adhesive")
		(11 "B.Adhes" user "B.Adhesive")
		(13 "F.Paste" user "Package Geometry/Pastemask Top")
		(15 "B.Paste" user "Package Geometry/Pastemask Bottom")
		(5 "F.SilkS" user "Ref Des/Silkscreen Top")
		(7 "B.SilkS" user "Ref Des/Silkscreen Bottom")
		(1 "F.Mask" user "Board Geometry/Soldermask Top")
		(3 "B.Mask" user "Board Geometry/Soldermask Bottom")
		(17 "Dwgs.User" user "User.Drawings")
		(19 "Cmts.User" user "User.Comments")
		(21 "Eco1.User" user "User.Eco1")
		(23 "Eco2.User" user "User.Eco2")
		(25 "Edge.Cuts" user "Board Geometry/Outline")
		(27 "Margin" user)
		(31 "F.CrtYd" user "Package Geometry/Place Bound Top")
		(29 "B.CrtYd" user "Package Geometry/Place Bound Bottom")
		(35 "F.Fab" user "Ref Des/Assembly Top")
		(33 "B.Fab" user "Ref Des/Assembly Bottom")
	)
	(footprint ""
		(layer "B.Cu")
		(at 230.66756 -214.704168 90)
		(property "Reference" "C2026"
			(at 0 0 90)
			(layer "B.SilkS")
			(hide yes)
			(effects
				(font
					(size 1.27 1.27)
				)
				(justify mirror)
			)
		)
		(property "Value" ""
			(at 0 0 90)
			(layer "B.Fab")
			(effects
				(font
					(size 1.27 1.27)
				)
				(justify mirror)
			)
		)
		(duplicate_pad_numbers_are_jumpers no)
		(fp_line
			(start 0.69215 -0.2921)
			(end -0.69215 -0.2921)
			(stroke
				(width 0.1524)
				(type default)
			)
			(layer "B.SilkS")
		)
		(fp_line
			(start -0.69215 -0.2921)
			(end -0.69215 0.2921)
			(stroke
				(width 0.1524)
				(type default)
			)
			(layer "B.SilkS")
		)
		(fp_line
			(start 0.69215 0.2921)
			(end 0.69215 -0.2921)
			(stroke
				(width 0.1524)
				(type default)
			)
			(layer "B.SilkS")
		)
		(fp_line
			(start -0.69215 0.2921)
			(end 0.69215 0.2921)
			(stroke
				(width 0.1524)
				(type default)
			)
			(layer "B.SilkS")
		)
		(fp_line
			(start 0.51435 -0.2794)
			(end -0.51435 -0.2794)
			(stroke
				(width 0.1)
				(type default)
			)
			(layer "B.Fab")
		)
		(fp_line
			(start -0.51435 -0.2794)
			(end -0.51435 0.2794)
			(stroke
				(width 0.1)
				(type default)
			)
			(layer "B.Fab")
		)
		(fp_line
			(start 0.51435 0.2794)
			(end 0.51435 -0.2794)
			(stroke
				(width 0.1)
				(type default)
			)
			(layer "B.Fab")
		)
		(fp_line
			(start -0.51435 0.2794)
			(end 0.51435 0.2794)
			(stroke
				(width 0.1)
				(type default)
			)
			(layer "B.Fab")
		)
		(pad "1" smd circle
			(at 0.40005 0 270)
			(size 0 0)
			(layers "B.Cu" "B.Mask" "B.Paste")
			(net "P3V3_AUX")
		)
		(pad "2" smd circle
			(at -0.40005 0 270)
			(size 0 0)
			(layers "B.Cu" "B.Mask" "B.Paste")
			(net "GND")
		)
		(zone
			(layer "B.Cu")
			(hatch none 0.5)
			(connect_pads
				(clearance 0)
			)
			(min_thickness 0.25)
			(keepout
				(tracks not_allowed)
				(vias allowed)
				(pads allowed)
				(copperpour not_allowed)
				(footprints allowed)
			)
			(placement
				(enabled no)
				(sheetname "")
			)
			(fill
				(thermal_gap 0.5)
				(thermal_bridge_width 0.5)
				(island_removal_mode 0)
			)
			(polygon
				(pts
					(xy 230.75519 -214.894668) (xy 230.813356 -214.803228) (xy 230.813356 -214.603838) (xy 230.75519 -214.513668)
					(xy 230.57993 -214.513668) (xy 230.52151 -214.603838) (xy 230.52151 -214.803228) (xy 230.579676 -214.894668)
				)
			)
		)
	)
	(footprint ""
		(layer "B.Cu")
		(at 172.424852 -293.99992 90)
		(property "Reference" "C1376"
			(at 0 0 90)
			(layer "B.SilkS")
			(hide yes)
			(effects
				(font
					(size 1.27 1.27)
				)
				(justify mirror)
			)
		)
		(property "Value" ""
			(at 0 0 90)
			(layer "B.Fab")
			(effects
				(font
					(size 1.27 1.27)
				)
				(justify mirror)
			)
		)
		(duplicate_pad_numbers_are_jumpers no)
		(fp_line
			(start 0.299974 -0.150114)
			(end -0.299974 -0.150114)
			(stroke
				(width 0.1)
				(type default)
			)
			(layer "B.Fab")
		)
		(fp_line
			(start -0.299974 -0.150114)
			(end -0.299974 0.150114)
			(stroke
				(width 0.1)
				(type default)
			)
			(layer "B.Fab")
		)
		(fp_line
			(start 0.299974 0.150114)
			(end 0.299974 -0.150114)
			(stroke
				(width 0.1)
				(type default)
			)
			(layer "B.Fab")
		)
		(fp_line
			(start -0.299974 0.150114)
			(end 0.299974 0.150114)
			(stroke
				(width 0.1)
				(type default)
			)
			(layer "B.Fab")
		)
		(pad "1" smd rect
			(at 0.2667 0 270)
			(size 0.3048 0.381)
			(layers "B.Cu" "B.Mask" "B.Paste")
			(net "P0V8_PEX1")
		)
		(pad "2" smd rect
			(at -0.2667 0 270)
			(size 0.3048 0.381)
			(layers "B.Cu" "B.Mask" "B.Paste")
			(net "GND")
		)
	)
	(footprint ""
		(layer "B.Cu")
		(at 378.164344 -226.47021 180)
		(property "Reference" "R6171"
			(at 0 0 0)
			(layer "B.SilkS")
			(hide yes)
			(effects
				(font
					(size 1.27 1.27)
				)
				(justify mirror)
			)
		)
		(property "Value" ""
			(at 0 0 0)
			(layer "B.Fab")
			(effects
				(font
					(size 1.27 1.27)
				)
				(justify mirror)
			)
		)
		(duplicate_pad_numbers_are_jumpers no)
		(fp_line
			(start 0.7874 0.4064)
			(end 0.7874 -0.4064)
			(stroke
				(width 0.1524)
				(type default)
			)
			(layer "B.SilkS")
		)
		(fp_line
			(start 0.7874 -0.4064)
			(end -0.7874 -0.4064)
			(stroke
				(width 0.1524)
				(type default)
			)
			(layer "B.SilkS")
		)
		(fp_line
			(start -0.7874 0.4064)
			(end 0.7874 0.4064)
			(stroke
				(width 0.1524)
				(type default)
			)
			(layer "B.SilkS")
		)
		(fp_line
			(start -0.7874 -0.4064)
			(end -0.7874 0.4064)
			(stroke
				(width 0.1524)
				(type default)
			)
			(layer "B.SilkS")
		)
		(fp_line
			(start 0.67945 0.3048)
			(end 0.67945 -0.305054)
			(stroke
				(width 0.1)
				(type default)
			)
			(layer "B.Fab")
		)
		(fp_line
			(start 0.67945 -0.305054)
			(end 0.12065 -0.305054)
			(stroke
				(width 0.1)
				(type default)
			)
			(layer "B.Fab")
		)
		(fp_line
			(start 0.12065 0.3048)
			(end 0.67945 0.3048)
			(stroke
				(width 0.1)
				(type default)
			)
			(layer "B.Fab")
		)
		(fp_line
			(start 0.12065 0.2794)
			(end 0.12065 0.3048)
			(stroke
				(width 0.1)
				(type default)
			)
			(layer "B.Fab")
		)
		(fp_line
			(start 0.12065 -0.2794)
			(end -0.12065 -0.2794)
			(stroke
				(width 0.1)
				(type default)
			)
			(layer "B.Fab")
		)
		(fp_line
			(start 0.12065 -0.305054)
			(end 0.12065 -0.2794)
			(stroke
				(width 0.1)
				(type default)
			)
			(layer "B.Fab")
		)
		(fp_line
			(start -0.120396 0.3048)
			(end -0.120396 0.2794)
			(stroke
				(width 0.1)
				(type default)
			)
			(layer "B.Fab")
		)
		(fp_line
			(start -0.120396 0.2794)
			(end 0.12065 0.2794)
			(stroke
				(width 0.1)
				(type default)
			)
			(layer "B.Fab")
		)
		(fp_line
			(start -0.12065 -0.2794)
			(end -0.12065 -0.3048)
			(stroke
				(width 0.1)
				(type default)
			)
			(layer "B.Fab")
		)
		(fp_line
			(start -0.12065 -0.3048)
			(end -0.67945 -0.3048)
			(stroke
				(width 0.1)
				(type default)
			)
			(layer "B.Fab")
		)
		(fp_line
			(start -0.67945 0.3048)
			(end -0.120396 0.3048)
			(stroke
				(width 0.1)
				(type default)
			)
			(layer "B.Fab")
		)
		(fp_line
			(start -0.67945 -0.3048)
			(end -0.67945 0.3048)
			(stroke
				(width 0.1)
				(type default)
			)
			(layer "B.Fab")
		)
		(pad "1" smd circle
			(at 0.40005 0)
			(size 0 0)
			(layers "B.Cu" "B.Mask" "B.Paste")
			(net "SPI_PEX3_RST_R_N")
		)
		(pad "2" smd circle
			(at -0.40005 0)
			(size 0 0)
			(layers "B.Cu" "B.Mask" "B.Paste")
			(net "SPI_PEX3_RST_N")
		)
	)
	(footprint ""
		(layer "B.Cu")
		(at 108.91139 -283.818584 90)
		(property "Reference" "PR99"
			(at 0 0 90)
			(layer "B.SilkS")
			(hide yes)
			(effects
				(font
					(size 1.27 1.27)
				)
				(justify mirror)
			)
		)
		(property "Value" ""
			(at 0 0 90)
			(layer "B.Fab")
			(effects
				(font
					(size 1.27 1.27)
				)
				(justify mirror)
			)
		)
		(duplicate_pad_numbers_are_jumpers no)
		(fp_line
			(start 0.7874 -0.4064)
			(end -0.7874 -0.4064)
			(stroke
				(width 0.1524)
				(type default)
			)
			(layer "B.SilkS")
		)
		(fp_line
			(start -0.7874 -0.4064)
			(end -0.7874 0.4064)
			(stroke
				(width 0.1524)
				(type default)
			)
			(layer "B.SilkS")
		)
		(fp_line
			(start 0.7874 0.4064)
			(end 0.7874 -0.4064)
			(stroke
				(width 0.1524)
				(type default)
			)
			(layer "B.SilkS")
		)
		(fp_line
			(start -0.7874 0.4064)
			(end 0.7874 0.4064)
			(stroke
				(width 0.1524)
				(type default)
			)
			(layer "B.SilkS")
		)
		(fp_line
			(start 0.67945 -0.305054)
			(end 0.12065 -0.305054)
			(stroke
				(width 0.1)
				(type default)
			)
			(layer "B.Fab")
		)
		(fp_line
			(start 0.12065 -0.305054)
			(end 0.12065 -0.2794)
			(stroke
				(width 0.1)
				(type default)
			)
			(layer "B.Fab")
		)
		(fp_line
			(start -0.12065 -0.3048)
			(end -0.67945 -0.3048)
			(stroke
				(width 0.1)
				(type default)
			)
			(layer "B.Fab")
		)
		(fp_line
			(start -0.67945 -0.3048)
			(end -0.67945 0.3048)
			(stroke
				(width 0.1)
				(type default)
			)
			(layer "B.Fab")
		)
		(fp_line
			(start 0.12065 -0.2794)
			(end -0.12065 -0.2794)
			(stroke
				(width 0.1)
				(type default)
			)
			(layer "B.Fab")
		)
		(fp_line
			(start -0.12065 -0.2794)
			(end -0.12065 -0.3048)
			(stroke
				(width 0.1)
				(type default)
			)
			(layer "B.Fab")
		)
		(fp_line
			(start 0.12065 0.2794)
			(end 0.12065 0.3048)
			(stroke
				(width 0.1)
				(type default)
			)
			(layer "B.Fab")
		)
		(fp_line
			(start -0.120396 0.2794)
			(end 0.12065 0.2794)
			(stroke
				(width 0.1)
				(type default)
			)
			(layer "B.Fab")
		)
		(fp_line
			(start 0.67945 0.3048)
			(end 0.67945 -0.305054)
			(stroke
				(width 0.1)
				(type default)
			)
			(layer "B.Fab")
		)
		(fp_line
			(start 0.12065 0.3048)
			(end 0.67945 0.3048)
			(stroke
				(width 0.1)
				(type default)
			)
			(layer "B.Fab")
		)
		(fp_line
			(start -0.120396 0.3048)
			(end -0.120396 0.2794)
			(stroke
				(width 0.1)
				(type default)
			)
			(layer "B.Fab")
		)
		(fp_line
			(start -0.67945 0.3048)
			(end -0.120396 0.3048)
			(stroke
				(width 0.1)
				(type default)
			)
			(layer "B.Fab")
		)
		(pad "1" smd circle
			(at 0.40005 0 270)
			(size 0 0)
			(layers "B.Cu" "B.Mask" "B.Paste")
			(net "P0V8_PEX0_PVCC")
		)
		(pad "2" smd circle
			(at -0.40005 0 270)
			(size 0 0)
			(layers "B.Cu" "B.Mask" "B.Paste")
			(net "P0V8_PEX0_VCC1")
		)
	)
	(footprint ""
		(layer "B.Cu")
		(at 409.374848 -293.99992 90)
		(property "Reference" "C1921"
			(at 0 0 90)
			(layer "B.SilkS")
			(hide yes)
			(effects
				(font
					(size 1.27 1.27)
				)
				(justify mirror)
			)
		)
		(property "Value" ""
			(at 0 0 90)
			(layer "B.Fab")
			(effects
				(font
					(size 1.27 1.27)
				)
				(justify mirror)
			)
		)
		(duplicate_pad_numbers_are_jumpers no)
		(fp_line
			(start 0.299974 -0.150114)
			(end -0.299974 -0.150114)
			(stroke
				(width 0.1)
				(type default)
			)
			(layer "B.Fab")
		)
		(fp_line
			(start -0.299974 -0.150114)
			(end -0.299974 0.150114)
			(stroke
				(width 0.1)
				(type default)
			)
			(layer "B.Fab")
		)
		(fp_line
			(start 0.299974 0.150114)
			(end 0.299974 -0.150114)
			(stroke
				(width 0.1)
				(type default)
			)
			(layer "B.Fab")
		)
		(fp_line
			(start -0.299974 0.150114)
			(end 0.299974 0.150114)
			(stroke
				(width 0.1)
				(type default)
			)
			(layer "B.Fab")
		)
		(pad "1" smd rect
			(at 0.2667 0 270)
			(size 0.3048 0.381)
			(layers "B.Cu" "B.Mask" "B.Paste")
			(net "P0V8_PEX3")
		)
		(pad "2" smd rect
			(at -0.2667 0 270)
			(size 0.3048 0.381)
			(layers "B.Cu" "B.Mask" "B.Paste")
			(net "GND")
		)
	)
	(footprint ""
		(layer "B.Cu")
		(at 72.208136 -300.174914 180)
		(property "Reference" "C3012"
			(at 0 0 0)
			(layer "B.SilkS")
			(hide yes)
			(effects
				(font
					(size 1.27 1.27)
				)
				(justify mirror)
			)
		)
		(property "Value" ""
			(at 0 0 0)
			(layer "B.Fab")
			(effects
				(font
					(size 1.27 1.27)
				)
				(justify mirror)
			)
		)
		(duplicate_pad_numbers_are_jumpers no)
		(fp_line
			(start 0.299974 0.150114)
			(end 0.299974 -0.150114)
			(stroke
				(width 0.1)
				(type default)
			)
			(layer "B.Fab")
		)
		(fp_line
			(start 0.299974 -0.150114)
			(end -0.299974 -0.150114)
			(stroke
				(width 0.1)
				(type default)
			)
			(layer "B.Fab")
		)
		(fp_line
			(start -0.299974 0.150114)
			(end 0.299974 0.150114)
			(stroke
				(width 0.1)
				(type default)
			)
			(layer "B.Fab")
		)
		(fp_line
			(start -0.299974 -0.150114)
			(end -0.299974 0.150114)
			(stroke
				(width 0.1)
				(type default)
			)
			(layer "B.Fab")
		)
		(pad "1" smd rect
			(at 0.2667 0)
			(size 0.3048 0.381)
			(layers "B.Cu" "B.Mask" "B.Paste")
			(net "P1V8_VDDA_PEX0")
		)
		(pad "2" smd rect
			(at -0.2667 0)
			(size 0.3048 0.381)
			(layers "B.Cu" "B.Mask" "B.Paste")
			(net "GND")
		)
	)
	(footprint ""
		(layer "B.Cu")
		(at 305.149758 -294.94988 180)
		(property "Reference" "C3297"
			(at 0 0 0)
			(layer "B.SilkS")
			(hide yes)
			(effects
				(font
					(size 1.27 1.27)
				)
				(justify mirror)
			)
		)
		(property "Value" ""
			(at 0 0 0)
			(layer "B.Fab")
			(effects
				(font
					(size 1.27 1.27)
				)
				(justify mirror)
			)
		)
		(duplicate_pad_numbers_are_jumpers no)
		(fp_line
			(start 0.299974 0.150114)
			(end 0.299974 -0.150114)
			(stroke
				(width 0.1)
				(type default)
			)
			(layer "B.Fab")
		)
		(fp_line
			(start 0.299974 -0.150114)
			(end -0.299974 -0.150114)
			(stroke
				(width 0.1)
				(type default)
			)
			(layer "B.Fab")
		)
		(fp_line
			(start -0.299974 0.150114)
			(end 0.299974 0.150114)
			(stroke
				(width 0.1)
				(type default)
			)
			(layer "B.Fab")
		)
		(fp_line
			(start -0.299974 -0.150114)
			(end -0.299974 0.150114)
			(stroke
				(width 0.1)
				(type default)
			)
			(layer "B.Fab")
		)
		(pad "1" smd rect
			(at 0.2667 0)
			(size 0.3048 0.381)
			(layers "B.Cu" "B.Mask" "B.Paste")
			(net "P1V25_SERDES_VDDPLL_PEX2")
		)
		(pad "2" smd rect
			(at -0.2667 0)
			(size 0.3048 0.381)
			(layers "B.Cu" "B.Mask" "B.Paste")
			(net "GND")
		)
	)
	(footprint ""
		(layer "B.Cu")
		(at 291.84981 -288.299906 90)
		(property "Reference" "C3289"
			(at 0 0 90)
			(layer "B.SilkS")
			(hide yes)
			(effects
				(font
					(size 1.27 1.27)
				)
				(justify mirror)
			)
		)
		(property "Value" ""
			(at 0 0 90)
			(layer "B.Fab")
			(effects
				(font
					(size 1.27 1.27)
				)
				(justify mirror)
			)
		)
		(duplicate_pad_numbers_are_jumpers no)
		(fp_line
			(start 0.299974 -0.150114)
			(end -0.299974 -0.150114)
			(stroke
				(width 0.1)
				(type default)
			)
			(layer "B.Fab")
		)
		(fp_line
			(start -0.299974 -0.150114)
			(end -0.299974 0.150114)
			(stroke
				(width 0.1)
				(type default)
			)
			(layer "B.Fab")
		)
		(fp_line
			(start 0.299974 0.150114)
			(end 0.299974 -0.150114)
			(stroke
				(width 0.1)
				(type default)
			)
			(layer "B.Fab")
		)
		(fp_line
			(start -0.299974 0.150114)
			(end 0.299974 0.150114)
			(stroke
				(width 0.1)
				(type default)
			)
			(layer "B.Fab")
		)
		(pad "1" smd rect
			(at 0.2667 0 270)
			(size 0.3048 0.381)
			(layers "B.Cu" "B.Mask" "B.Paste")
			(net "P1V25_PEX2")
		)
		(pad "2" smd rect
			(at -0.2667 0 270)
			(size 0.3048 0.381)
			(layers "B.Cu" "B.Mask" "B.Paste")
			(net "GND")
		)
	)
	(footprint ""
		(layer "B.Cu")
		(at 174.325026 -297.79976 -90)
		(property "Reference" "C1383"
			(at 0 0 90)
			(layer "B.SilkS")
			(hide yes)
			(effects
				(font
					(size 1.27 1.27)
				)
				(justify mirror)
			)
		)
		(property "Value" ""
			(at 0 0 90)
			(layer "B.Fab")
			(effects
				(font
					(size 1.27 1.27)
				)
				(justify mirror)
			)
		)
		(duplicate_pad_numbers_are_jumpers no)
		(fp_line
			(start -0.299974 0.150114)
			(end 0.299974 0.150114)
			(stroke
				(width 0.1)
				(type default)
			)
			(layer "B.Fab")
		)
		(fp_line
			(start 0.299974 0.150114)
			(end 0.299974 -0.150114)
			(stroke
				(width 0.1)
				(type default)
			)
			(layer "B.Fab")
		)
		(fp_line
			(start -0.299974 -0.150114)
			(end -0.299974 0.150114)
			(stroke
				(width 0.1)
				(type default)
			)
			(layer "B.Fab")
		)
		(fp_line
			(start 0.299974 -0.150114)
			(end -0.299974 -0.150114)
			(stroke
				(width 0.1)
				(type default)
			)
			(layer "B.Fab")
		)
		(pad "1" smd rect
			(at 0.2667 0 90)
			(size 0.3048 0.381)
			(layers "B.Cu" "B.Mask" "B.Paste")
			(net "P0V8_PEX1")
		)
		(pad "2" smd rect
			(at -0.2667 0 90)
			(size 0.3048 0.381)
			(layers "B.Cu" "B.Mask" "B.Paste")
			(net "GND")
		)
	)
	(footprint ""
		(layer "B.Cu")
		(at 340.671404 -323.15531 -90)
		(property "Reference" "R6516"
			(at 0 0 90)
			(layer "B.SilkS")
			(hide yes)
			(effects
				(font
					(size 1.27 1.27)
				)
				(justify mirror)
			)
		)
		(property "Value" ""
			(at 0 0 90)
			(layer "B.Fab")
			(effects
				(font
					(size 1.27 1.27)
				)
				(justify mirror)
			)
		)
		(duplicate_pad_numbers_are_jumpers no)
		(fp_line
			(start -0.7874 0.4064)
			(end 0.7874 0.4064)
			(stroke
				(width 0.1524)
				(type default)
			)
			(layer "B.SilkS")
		)
		(fp_line
			(start 0.7874 0.4064)
			(end 0.7874 -0.4064)
			(stroke
				(width 0.1524)
				(type default)
			)
			(layer "B.SilkS")
		)
		(fp_line
			(start -0.7874 -0.4064)
			(end -0.7874 0.4064)
			(stroke
				(width 0.1524)
				(type default)
			)
			(layer "B.SilkS")
		)
		(fp_line
			(start 0.7874 -0.4064)
			(end -0.7874 -0.4064)
			(stroke
				(width 0.1524)
				(type default)
			)
			(layer "B.SilkS")
		)
		(fp_line
			(start -0.67945 0.3048)
			(end -0.120396 0.3048)
			(stroke
				(width 0.1)
				(type default)
			)
			(layer "B.Fab")
		)
		(fp_line
			(start -0.120396 0.3048)
			(end -0.120396 0.2794)
			(stroke
				(width 0.1)
				(type default)
			)
			(layer "B.Fab")
		)
		(fp_line
			(start 0.12065 0.3048)
			(end 0.67945 0.3048)
			(stroke
				(width 0.1)
				(type default)
			)
			(layer "B.Fab")
		)
		(fp_line
			(start 0.67945 0.3048)
			(end 0.67945 -0.305054)
			(stroke
				(width 0.1)
				(type default)
			)
			(layer "B.Fab")
		)
		(fp_line
			(start -0.120396 0.2794)
			(end 0.12065 0.2794)
			(stroke
				(width 0.1)
				(type default)
			)
			(layer "B.Fab")
		)
		(fp_line
			(start 0.12065 0.2794)
			(end 0.12065 0.3048)
			(stroke
				(width 0.1)
				(type default)
			)
			(layer "B.Fab")
		)
		(fp_line
			(start -0.12065 -0.2794)
			(end -0.12065 -0.3048)
			(stroke
				(width 0.1)
				(type default)
			)
			(layer "B.Fab")
		)
		(fp_line
			(start 0.12065 -0.2794)
			(end -0.12065 -0.2794)
			(stroke
				(width 0.1)
				(type default)
			)
			(layer "B.Fab")
		)
		(fp_line
			(start -0.67945 -0.3048)
			(end -0.67945 0.3048)
			(stroke
				(width 0.1)
				(type default)
			)
			(layer "B.Fab")
		)
		(fp_line
			(start -0.12065 -0.3048)
			(end -0.67945 -0.3048)
			(stroke
				(width 0.1)
				(type default)
			)
			(layer "B.Fab")
		)
		(fp_line
			(start 0.12065 -0.305054)
			(end 0.12065 -0.2794)
			(stroke
				(width 0.1)
				(type default)
			)
			(layer "B.Fab")
		)
		(fp_line
			(start 0.67945 -0.305054)
			(end 0.12065 -0.305054)
			(stroke
				(width 0.1)
				(type default)
			)
			(layer "B.Fab")
		)
		(pad "1" smd circle
			(at 0.40005 0 90)
			(size 0 0)
			(layers "B.Cu" "B.Mask" "B.Paste")
			(net "P0V8_SERDES_VDDA_PEX2")
		)
		(pad "2" smd circle
			(at -0.40005 0 90)
			(size 0 0)
			(layers "B.Cu" "B.Mask" "B.Paste")
			(net "P0V8_SERDES_VDDA_PEX2_C9")
		)
	)
)
